#ISCELL
  mstr_misc dns *
  *
#ISCELL
  pure_quanta quanta_title_block_c *
  *
#ISCELL
  standard offpage *
  page191_i1
#ISCELL
  pure_quanta_power universal_gnd *
  page191_i16
#CELL
  pure_quanta q_res *
  page191_i17
#CELL
  pure_quanta q_res *
  page191_i18
#ISCELL
  pure_quanta_power universal_gnd *
  page191_i2
#CELL
  pure_quanta q_cap *
  page191_i20
#CELL
  pure_quanta q_cap *
  page191_i21
#CELL
  pure_quanta q_cap *
  page191_i22
#ISCELL
  pure_quanta_power universal_gnd *
  page191_i23
#CELL
  pure_quanta q_cap *
  page191_i25
#CELL
  pure_quanta q_cap *
  page191_i26
#ISCELL
  pure_quanta_power vcc_core *
  page191_i27
#ISCELL
  pure_quanta_power universal_gnd *
  page191_i28
#CELL
  pure_quanta q_cap *
  page191_i29
#ISCELL
  pure_quanta_power universal_gnd *
  page191_i3
#ISCELL
  pure_quanta_power vcc_core *
  page191_i30
#CELL
  pure_quanta q_inductor4p_14 *
  page191_i31
#CELL
  pure_quanta q_cap *
  page191_i32
#CELL
  pure_quanta isl99390frztr5935 *
  page191_i34
#CELL
  pure_quanta q_cap *
  page191_i37
#CELL
  pure_quanta q_cap *
  page191_i38
#ISCELL
  pure_quanta_power universal_gnd *
  page191_i39
#ISCELL
  standard offpage *
  page191_i4
#ISCELL
  pure_quanta_power universal_gnd *
  page191_i40
#CELL
  pure_quanta q_res *
  page191_i41
#CELL
  pure_quanta q_cap *
  page191_i42
#ISCELL
  pure_quanta_power vcc_core *
  page191_i43
#ISCELL
  pure_quanta_power universal_gnd *
  page191_i45
#CELL
  pure_quanta q_res *
  page191_i46
#CELL
  pure_quanta q_cap *
  page191_i47
#CELL
  pure_quanta q_cap *
  page191_i48
#ISCELL
  standard offpage *
  page191_i5
#ISCELL
  standard offpage *
  page191_i51
#CELL
  pure_quanta q_inductor *
  page191_i52
#ISCELL
  pure_quanta_power universal_gnd *
  page191_i53
#CELL
  pure_quanta q_cap *
  page191_i6
#CELL
  pure_quanta q_res *
  page191_i7
#ISCELL
  standard offpage *
  page191_i8
